# S9S_MB_2U (Grand Teton) — schematic netlist excerpt (pin names and nets, part order shuffled) for the footprints in the layout excerpt that follows; sources: Cadence DE-HDL packaged netlist, KiCad conversion of 03242023_DA0F0TMBIJ0_F0T_Motherboard_J_brd_V01_OCP.brd

C850  Q_CAP_DIFFBUS  DIFF BUS_0.22UF 6.3V 20% X6S  pkg C0201  page 174 : \1\ = P5E_CPU0_PE1_TX_C_DN<9> ; \2\ = P5E_CPU0_PE1_TX_DN<9>
PC1367  Q_CAP  0.1UF 25V 10% X7R  pkg 0402  page 289 : A = GND ; B = PVCCIN_CPU1_VREF

(kicad_pcb
	(version 20260206)
	(generator "pcbnew")
	(generator_version "10.0")
	(general
		(thickness 1.6)
		(legacy_teardrops no)
	)
	(paper "A4")
	(title_block
		(title "03242023_DA0F0TMBIJ0_F0T_Motherboard_J_brd_V01_OCP.brd")
		(comment 1 "Grand Teton / footprints 376-377 of 6105")
	)
	(layers
		(0 "F.Cu" signal "TOP")
		(4 "In1.Cu" signal "GND")
		(6 "In2.Cu" signal "IN1")
		(8 "In3.Cu" signal "GND1")
		(10 "In4.Cu" signal "IN2")
		(12 "In5.Cu" signal "GND2")
		(14 "In6.Cu" signal "IN3")
		(16 "In7.Cu" signal "GND3")
		(18 "In8.Cu" signal "VCC")
		(20 "In9.Cu" signal "VCC1")
		(22 "In10.Cu" signal "GND4")
		(24 "In11.Cu" signal "IN4")
		(26 "In12.Cu" signal "GND5")
		(28 "In13.Cu" signal "IN5")
		(30 "In14.Cu" signal "GND6")
		(32 "In15.Cu" signal "IN6")
		(34 "In16.Cu" signal "GND7")
		(2 "B.Cu" signal "BOTTOM")
		(9 "F.Adhes" user "F.Adhesive")
		(11 "B.Adhes" user "B.Adhesive")
		(13 "F.Paste" user "Package Geometry/Pastemask Top")
		(15 "B.Paste" user "Package Geometry/Pastemask Bottom")
		(5 "F.SilkS" user "Ref Des/Silkscreen Top")
		(7 "B.SilkS" user "Ref Des/Silkscreen Bottom")
		(1 "F.Mask" user "Board Geometry/Soldermask Top")
		(3 "B.Mask" user "Board Geometry/Soldermask Bottom")
		(17 "Dwgs.User" user "User.Drawings")
		(19 "Cmts.User" user "User.Comments")
		(21 "Eco1.User" user "User.Eco1")
		(23 "Eco2.User" user "User.Eco2")
		(25 "Edge.Cuts" user "Board Geometry/Outline")
		(27 "Margin" user)
		(31 "F.CrtYd" user "Package Geometry/Place Bound Top")
		(29 "B.CrtYd" user "Package Geometry/Place Bound Bottom")
		(35 "F.Fab" user "Ref Des/Assembly Top")
		(33 "B.Fab" user "Ref Des/Assembly Bottom")
	)
	(footprint ""
		(layer "F.Cu")
		(at 169.27195 -358.135936 -90)
		(property "Reference" "PC1367"
			(at 0 0 270)
			(layer "F.SilkS")
			(hide yes)
			(effects
				(font
					(size 1.27 1.27)
				)
			)
		)
		(property "Value" ""
			(at 0 0 270)
			(layer "F.Fab")
			(effects
				(font
					(size 1.27 1.27)
				)
			)
		)
		(duplicate_pad_numbers_are_jumpers no)
		(fp_line
			(start -0.7874 0.4064)
			(end -0.7874 -0.4064)
			(stroke
				(width 0.1524)
				(type default)
			)
			(layer "F.SilkS")
		)
		(fp_line
			(start 0.7874 0.4064)
			(end -0.7874 0.4064)
			(stroke
				(width 0.1524)
				(type default)
			)
			(layer "F.SilkS")
		)
		(fp_line
			(start -0.7874 -0.4064)
			(end 0.7874 -0.4064)
			(stroke
				(width 0.1524)
				(type default)
			)
			(layer "F.SilkS")
		)
		(fp_line
			(start 0.7874 -0.4064)
			(end 0.7874 0.4064)
			(stroke
				(width 0.1524)
				(type default)
			)
			(layer "F.SilkS")
		)
		(fp_line
			(start -0.67945 0.3048)
			(end -0.67945 -0.305054)
			(stroke
				(width 0.1)
				(type default)
			)
			(layer "F.Fab")
		)
		(fp_line
			(start -0.12065 0.3048)
			(end -0.67945 0.3048)
			(stroke
				(width 0.1)
				(type default)
			)
			(layer "F.Fab")
		)
		(fp_line
			(start 0.120396 0.3048)
			(end 0.120396 0.2794)
			(stroke
				(width 0.1)
				(type default)
			)
			(layer "F.Fab")
		)
		(fp_line
			(start 0.67945 0.3048)
			(end 0.120396 0.3048)
			(stroke
				(width 0.1)
				(type default)
			)
			(layer "F.Fab")
		)
		(fp_line
			(start -0.12065 0.2794)
			(end -0.12065 0.3048)
			(stroke
				(width 0.1)
				(type default)
			)
			(layer "F.Fab")
		)
		(fp_line
			(start 0.120396 0.2794)
			(end -0.12065 0.2794)
			(stroke
				(width 0.1)
				(type default)
			)
			(layer "F.Fab")
		)
		(fp_line
			(start -0.12065 -0.2794)
			(end 0.12065 -0.2794)
			(stroke
				(width 0.1)
				(type default)
			)
			(layer "F.Fab")
		)
		(fp_line
			(start 0.12065 -0.2794)
			(end 0.12065 -0.3048)
			(stroke
				(width 0.1)
				(type default)
			)
			(layer "F.Fab")
		)
		(fp_line
			(start 0.12065 -0.3048)
			(end 0.67945 -0.3048)
			(stroke
				(width 0.1)
				(type default)
			)
			(layer "F.Fab")
		)
		(fp_line
			(start 0.67945 -0.3048)
			(end 0.67945 0.3048)
			(stroke
				(width 0.1)
				(type default)
			)
			(layer "F.Fab")
		)
		(fp_line
			(start -0.67945 -0.305054)
			(end -0.12065 -0.305054)
			(stroke
				(width 0.1)
				(type default)
			)
			(layer "F.Fab")
		)
		(fp_line
			(start -0.12065 -0.305054)
			(end -0.12065 -0.2794)
			(stroke
				(width 0.1)
				(type default)
			)
			(layer "F.Fab")
		)
		(pad "1" smd circle
			(at -0.40005 0 270)
			(size 0 0)
			(layers "F.Cu" "F.Mask" "F.Paste")
			(net "GND")
		)
		(pad "2" smd circle
			(at 0.40005 0 270)
			(size 0 0)
			(layers "F.Cu" "F.Mask" "F.Paste")
			(net "PVCCIN_CPU1_VREF")
		)
	)
	(footprint ""
		(layer "F.Cu")
		(at 407.694384 -16.088614 90)
		(property "Reference" "C850"
			(at 0 0 90)
			(layer "F.SilkS")
			(hide yes)
			(effects
				(font
					(size 1.27 1.27)
				)
			)
		)
		(property "Value" ""
			(at 0 0 90)
			(layer "F.Fab")
			(effects
				(font
					(size 1.27 1.27)
				)
			)
		)
		(duplicate_pad_numbers_are_jumpers no)
		(fp_line
			(start 0.299974 -0.150114)
			(end 0.299974 0.150114)
			(stroke
				(width 0.1)
				(type default)
			)
			(layer "F.Fab")
		)
		(fp_line
			(start -0.299974 -0.150114)
			(end 0.299974 -0.150114)
			(stroke
				(width 0.1)
				(type default)
			)
			(layer "F.Fab")
		)
		(fp_line
			(start 0.299974 0.150114)
			(end -0.299974 0.150114)
			(stroke
				(width 0.1)
				(type default)
			)
			(layer "F.Fab")
		)
		(fp_line
			(start -0.299974 0.150114)
			(end -0.299974 -0.150114)
			(stroke
				(width 0.1)
				(type default)
			)
			(layer "F.Fab")
		)
		(pad "1" smd rect
			(at -0.2667 0 90)
			(size 0.3048 0.381)
			(layers "F.Cu" "F.Mask" "F.Paste")
			(net "P5E_CPU0_PE1_TX_C_DN<9>")
		)
		(pad "2" smd rect
			(at 0.2667 0 90)
			(size 0.3048 0.381)
			(layers "F.Cu" "F.Mask" "F.Paste")
			(net "P5E_CPU0_PE1_TX_DN<9>")
		)
	)
)
